(kicad_pcb
	(version 20260206)
	(generator "pcbnew")
	(generator_version "10.0")
	(general
		(thickness 1.6)
		(legacy_teardrops no)
	)
	(paper "A4")
	(title_block
		(title "timecard-production-celestica-r4006 — R4006-B0001-02_R01.brd")
		(comment 1 "Time Appliance Project (Time Card) / footprints 821-826 of 1113")
	)
	(layers
		(0 "F.Cu" signal "TOP")
		(4 "In1.Cu" signal "L02_GND1")
		(6 "In2.Cu" signal "L03_SIG1")
		(8 "In3.Cu" signal "L04_GND2")
		(10 "In4.Cu" signal "L05_VCC1")
		(12 "In5.Cu" signal "L06_VCC2")
		(14 "In6.Cu" signal "L07_GND3")
		(16 "In7.Cu" signal "L08_SIG2")
		(18 "In8.Cu" signal "L09_GND4")
		(2 "B.Cu" signal "BOTTOM")
		(9 "F.Adhes" user "F.Adhesive")
		(11 "B.Adhes" user "B.Adhesive")
		(13 "F.Paste" user "Package Geometry/Pastemask Top")
		(15 "B.Paste" user "Package Geometry/Pastemask Bottom")
		(5 "F.SilkS" user "Ref Des/Silkscreen Top")
		(7 "B.SilkS" user "Ref Des/Silkscreen Bottom")
		(1 "F.Mask" user "Board Geometry/Soldermask Top")
		(3 "B.Mask" user "Board Geometry/Soldermask Bottom")
		(17 "Dwgs.User" user "User.Drawings")
		(19 "Cmts.User" user "User.Comments")
		(21 "Eco1.User" user "User.Eco1")
		(23 "Eco2.User" user "User.Eco2")
		(25 "Edge.Cuts" user "Board Geometry/Outline")
		(27 "Margin" user)
		(31 "F.CrtYd" user "Package Geometry/Place Bound Top")
		(29 "B.CrtYd" user "Package Geometry/Place Bound Bottom")
		(35 "F.Fab" user "Ref Des/Assembly Top")
		(33 "B.Fab" user "Ref Des/Assembly Bottom")
	)
	(footprint ""
		(layer "B.Cu")
		(at 111.633 -61.976 90)
		(property "Reference" "R219"
			(at 3.302 -0.03937 270)
			(unlocked yes)
			(layer "B.SilkS")
			(effects
				(font
					(size 0.7874 0.5842)
					(thickness 0.1524)
				)
				(justify mirror)
			)
		)
		(property "Value" "VAL*"
			(at -0.02032 2.13233 90)
			(unlocked yes)
			(layer "B.Fab")
			(hide yes)
			(effects
				(font
					(size 0.7874 0.5842)
					(thickness 0.1524)
				)
				(justify mirror)
			)
		)
		(property "Device Type" "RESISTOR-G155-11002-01,10KOHM,A"
			(at -0.008382 1.210564 90)
			(unlocked yes)
			(layer "B.Fab")
			(hide yes)
			(effects
				(font
					(size 0.7874 0.5842)
					(thickness 0.1524)
				)
				(justify mirror)
			)
		)
		(property "User Part Number" "PARTNUM*"
			(at -0.02032 4.024884 90)
			(unlocked yes)
			(layer "Cmts.User")
			(hide yes)
			(effects
				(font
					(size 0.7874 0.5842)
					(thickness 0.1524)
				)
				(justify mirror)
			)
		)
		(property "Tolerance" "TOL*"
			(at -0.044704 3.05435 90)
			(unlocked yes)
			(layer "Cmts.User")
			(hide yes)
			(effects
				(font
					(size 0.7874 0.5842)
					(thickness 0.1524)
				)
				(justify mirror)
			)
		)
		(duplicate_pad_numbers_are_jumpers no)
		(fp_line
			(start 1.143 -0.5588)
			(end 1.143 0.5588)
			(stroke
				(width 0.1)
				(type default)
			)
			(layer "B.SilkS")
		)
		(fp_line
			(start -1.143 -0.5588)
			(end 1.143 -0.5588)
			(stroke
				(width 0.1)
				(type default)
			)
			(layer "B.SilkS")
		)
		(fp_line
			(start 1.143 0.5588)
			(end -1.143 0.5588)
			(stroke
				(width 0.1)
				(type default)
			)
			(layer "B.SilkS")
		)
		(fp_line
			(start -1.143 0.5588)
			(end -1.143 -0.5588)
			(stroke
				(width 0.1)
				(type default)
			)
			(layer "B.SilkS")
		)
		(fp_rect
			(start -1.143 0.5588)
			(end 1.143 -0.5588)
			(stroke
				(width 0)
				(type default)
			)
			(fill no)
			(layer "B.CrtYd")
		)
		(fp_line
			(start 0.508 -0.3048)
			(end 0.508 0.3048)
			(stroke
				(width 0.1)
				(type default)
			)
			(layer "B.Fab")
		)
		(fp_line
			(start -0.508 -0.3048)
			(end 0.508 -0.3048)
			(stroke
				(width 0.1)
				(type default)
			)
			(layer "B.Fab")
		)
		(fp_line
			(start 0.508 0.3048)
			(end -0.508 0.3048)
			(stroke
				(width 0.1)
				(type default)
			)
			(layer "B.Fab")
		)
		(fp_line
			(start -0.508 0.3048)
			(end -0.508 -0.3048)
			(stroke
				(width 0.1)
				(type default)
			)
			(layer "B.Fab")
		)
		(pad "1" smd rect
			(at 0.5334 0 270)
			(size 0.7112 0.6096)
			(layers "B.Cu" "B.Mask" "B.Paste")
			(net "XP3R3V_FPGA")
		)
		(pad "2" smd rect
			(at -0.5334 0 270)
			(size 0.7112 0.6096)
			(layers "B.Cu" "B.Mask" "B.Paste")
			(net "FPGA_BRD_REV0")
		)
		(zone
			(layer "B.Cu")
			(hatch none 0.5)
			(connect_pads
				(clearance 0)
			)
			(min_thickness 0.25)
			(keepout
				(tracks allowed)
				(vias not_allowed)
				(pads allowed)
				(copperpour not_allowed)
				(footprints allowed)
			)
			(placement
				(enabled no)
				(sheetname "")
			)
			(fill
				(thermal_gap 0.5)
				(thermal_bridge_width 0.5)
				(island_removal_mode 0)
			)
			(polygon
				(pts
					(xy 111.9378 -61.8998) (xy 111.9378 -62.0522) (xy 111.3282 -62.0522) (xy 111.3282 -61.8998)
				)
			)
		)
	)
	(footprint ""
		(layer "B.Cu")
		(at 26.797 -94.234 90)
		(property "Reference" "R18"
			(at 2.54 0.34163 270)
			(unlocked yes)
			(layer "B.SilkS")
			(effects
				(font
					(size 0.7874 0.5842)
					(thickness 0.1524)
				)
				(justify mirror)
			)
		)
		(property "Value" "VAL*"
			(at -0.02032 2.13233 90)
			(unlocked yes)
			(layer "B.Fab")
			(hide yes)
			(effects
				(font
					(size 0.7874 0.5842)
					(thickness 0.1524)
				)
				(justify mirror)
			)
		)
		(property "Device Type" "RESISTOR-G155-14701-01,4.7KOHMA"
			(at -0.008382 1.210564 90)
			(unlocked yes)
			(layer "B.Fab")
			(hide yes)
			(effects
				(font
					(size 0.7874 0.5842)
					(thickness 0.1524)
				)
				(justify mirror)
			)
		)
		(property "User Part Number" "PARTNUM*"
			(at -0.02032 4.024884 90)
			(unlocked yes)
			(layer "Cmts.User")
			(hide yes)
			(effects
				(font
					(size 0.7874 0.5842)
					(thickness 0.1524)
				)
				(justify mirror)
			)
		)
		(property "Tolerance" "TOL*"
			(at -0.044704 3.05435 90)
			(unlocked yes)
			(layer "Cmts.User")
			(hide yes)
			(effects
				(font
					(size 0.7874 0.5842)
					(thickness 0.1524)
				)
				(justify mirror)
			)
		)
		(duplicate_pad_numbers_are_jumpers no)
		(fp_line
			(start 1.143 -0.5588)
			(end 1.143 0.5588)
			(stroke
				(width 0.1)
				(type default)
			)
			(layer "B.SilkS")
		)
		(fp_line
			(start -1.143 -0.5588)
			(end 1.143 -0.5588)
			(stroke
				(width 0.1)
				(type default)
			)
			(layer "B.SilkS")
		)
		(fp_line
			(start 1.143 0.5588)
			(end -1.143 0.5588)
			(stroke
				(width 0.1)
				(type default)
			)
			(layer "B.SilkS")
		)
		(fp_line
			(start -1.143 0.5588)
			(end -1.143 -0.5588)
			(stroke
				(width 0.1)
				(type default)
			)
			(layer "B.SilkS")
		)
		(fp_rect
			(start -1.143 0.5588)
			(end 1.143 -0.5588)
			(stroke
				(width 0)
				(type default)
			)
			(fill no)
			(layer "B.CrtYd")
		)
		(fp_line
			(start 0.508 -0.3048)
			(end 0.508 0.3048)
			(stroke
				(width 0.1)
				(type default)
			)
			(layer "B.Fab")
		)
		(fp_line
			(start -0.508 -0.3048)
			(end 0.508 -0.3048)
			(stroke
				(width 0.1)
				(type default)
			)
			(layer "B.Fab")
		)
		(fp_line
			(start 0.508 0.3048)
			(end -0.508 0.3048)
			(stroke
				(width 0.1)
				(type default)
			)
			(layer "B.Fab")
		)
		(fp_line
			(start -0.508 0.3048)
			(end -0.508 -0.3048)
			(stroke
				(width 0.1)
				(type default)
			)
			(layer "B.Fab")
		)
		(pad "1" smd rect
			(at 0.5334 0 270)
			(size 0.7112 0.6096)
			(layers "B.Cu" "B.Mask" "B.Paste")
			(net "XP5R0V_FT4232")
		)
		(pad "2" smd rect
			(at -0.5334 0 270)
			(size 0.7112 0.6096)
			(layers "B.Cu" "B.Mask" "B.Paste")
			(net "FT_USB_DETECT")
		)
		(zone
			(layer "B.Cu")
			(hatch none 0.5)
			(connect_pads
				(clearance 0)
			)
			(min_thickness 0.25)
			(keepout
				(tracks allowed)
				(vias not_allowed)
				(pads allowed)
				(copperpour not_allowed)
				(footprints allowed)
			)
			(placement
				(enabled no)
				(sheetname "")
			)
			(fill
				(thermal_gap 0.5)
				(thermal_bridge_width 0.5)
				(island_removal_mode 0)
			)
			(polygon
				(pts
					(xy 27.1018 -94.1578) (xy 27.1018 -94.3102) (xy 26.4922 -94.3102) (xy 26.4922 -94.1578)
				)
			)
		)
	)
	(footprint ""
		(layer "B.Cu")
		(at 107.823 -103.251 180)
		(property "Reference" "R317"
			(at -0.127 3.13563 0)
			(unlocked yes)
			(layer "B.SilkS")
			(effects
				(font
					(size 0.7874 0.5842)
					(thickness 0.1524)
				)
				(justify mirror)
			)
		)
		(property "Value" "VAL*"
			(at -0.02032 2.13233 180)
			(unlocked yes)
			(layer "B.Fab")
			(hide yes)
			(effects
				(font
					(size 0.7874 0.5842)
					(thickness 0.1524)
				)
				(justify mirror)
			)
		)
		(property "Tolerance" "TOL*"
			(at -0.044704 3.05435 180)
			(unlocked yes)
			(layer "Cmts.User")
			(hide yes)
			(effects
				(font
					(size 0.7874 0.5842)
					(thickness 0.1524)
				)
				(justify mirror)
			)
		)
		(property "User Part Number" "PARTNUM*"
			(at -0.02032 4.024884 180)
			(unlocked yes)
			(layer "Cmts.User")
			(hide yes)
			(effects
				(font
					(size 0.7874 0.5842)
					(thickness 0.1524)
				)
				(justify mirror)
			)
		)
		(property "Device Type" "RESISTOR-G155-11002-01,10KOHM,A"
			(at -0.008382 1.210564 180)
			(unlocked yes)
			(layer "B.Fab")
			(hide yes)
			(effects
				(font
					(size 0.7874 0.5842)
					(thickness 0.1524)
				)
				(justify mirror)
			)
		)
		(duplicate_pad_numbers_are_jumpers no)
		(fp_line
			(start 1.143 0.5588)
			(end -1.143 0.5588)
			(stroke
				(width 0.1)
				(type default)
			)
			(layer "B.SilkS")
		)
		(fp_line
			(start 1.143 -0.5588)
			(end 1.143 0.5588)
			(stroke
				(width 0.1)
				(type default)
			)
			(layer "B.SilkS")
		)
		(fp_line
			(start -1.143 0.5588)
			(end -1.143 -0.5588)
			(stroke
				(width 0.1)
				(type default)
			)
			(layer "B.SilkS")
		)
		(fp_line
			(start -1.143 -0.5588)
			(end 1.143 -0.5588)
			(stroke
				(width 0.1)
				(type default)
			)
			(layer "B.SilkS")
		)
		(fp_poly
			(pts
				(xy 1.143 0.5588) (xy -1.143 0.5588) (xy -1.143 -0.5588) (xy 1.143 -0.5588)
			)
			(stroke
				(width 0)
				(type default)
			)
			(fill no)
			(layer "B.CrtYd")
		)
		(fp_line
			(start 0.508 0.3048)
			(end -0.508 0.3048)
			(stroke
				(width 0.1)
				(type default)
			)
			(layer "B.Fab")
		)
		(fp_line
			(start 0.508 -0.3048)
			(end 0.508 0.3048)
			(stroke
				(width 0.1)
				(type default)
			)
			(layer "B.Fab")
		)
		(fp_line
			(start -0.508 0.3048)
			(end -0.508 -0.3048)
			(stroke
				(width 0.1)
				(type default)
			)
			(layer "B.Fab")
		)
		(fp_line
			(start -0.508 -0.3048)
			(end 0.508 -0.3048)
			(stroke
				(width 0.1)
				(type default)
			)
			(layer "B.Fab")
		)
		(pad "1" smd rect
			(at 0.5334 0)
			(size 0.7112 0.6096)
			(layers "B.Cu" "B.Mask" "B.Paste")
			(net "XP3R3V_FPGA")
		)
		(pad "2" smd rect
			(at -0.5334 0)
			(size 0.7112 0.6096)
			(layers "B.Cu" "B.Mask" "B.Paste")
			(net "R_RGB_LED_I2C_SDA")
		)
		(zone
			(layer "B.Cu")
			(hatch none 0.5)
			(connect_pads
				(clearance 0)
			)
			(min_thickness 0.25)
			(keepout
				(tracks allowed)
				(vias not_allowed)
				(pads allowed)
				(copperpour not_allowed)
				(footprints allowed)
			)
			(placement
				(enabled no)
				(sheetname "")
			)
			(fill
				(thermal_gap 0.5)
				(thermal_bridge_width 0.5)
				(island_removal_mode 0)
			)
			(polygon
				(pts
					(xy 107.7468 -103.5558) (xy 107.7468 -102.9462) (xy 107.8992 -102.9462) (xy 107.8992 -103.5558)
				)
			)
		)
		(zone
			(layer "B.Cu")
			(hatch none 0.5)
			(connect_pads
				(clearance 0)
			)
			(min_thickness 0.25)
			(keepout
				(tracks not_allowed)
				(vias allowed)
				(pads allowed)
				(copperpour not_allowed)
				(footprints allowed)
			)
			(placement
				(enabled no)
				(sheetname "")
			)
			(fill
				(thermal_gap 0.5)
				(thermal_bridge_width 0.5)
				(island_removal_mode 0)
			)
			(polygon
				(pts
					(xy 107.7468 -103.5558) (xy 107.7468 -102.9462) (xy 107.8992 -102.9462) (xy 107.8992 -103.5558)
				)
			)
		)
	)
	(footprint ""
		(layer "B.Cu")
		(at 118.346982 -39.823136)
		(property "Reference" "C151"
			(at 2.303018 -0.404114 0)
			(unlocked yes)
			(layer "B.SilkS")
			(effects
				(font
					(size 0.635 0.4064)
					(thickness 0.1524)
				)
				(justify mirror)
			)
		)
		(property "Value" "VAL*"
			(at 0 3.718306 0)
			(unlocked yes)
			(layer "B.Fab")
			(hide yes)
			(effects
				(font
					(size 0.7874 0.5842)
					(thickness 0.127)
				)
				(justify mirror)
			)
		)
		(property "Tolerance" "TOL*"
			(at 0 4.861306 0)
			(unlocked yes)
			(layer "Cmts.User")
			(hide yes)
			(effects
				(font
					(size 0.7874 0.5842)
					(thickness 0.127)
				)
				(justify mirror)
			)
		)
		(property "User Part Number" "PARTNUM*"
			(at 0 2.575306 0)
			(unlocked yes)
			(layer "Cmts.User")
			(hide yes)
			(effects
				(font
					(size 0.7874 0.5842)
					(thickness 0.127)
				)
				(justify mirror)
			)
		)
		(property "Device Type" "CAPACITOR-G105-0B104-CK,0.1UF,A"
			(at 0 1.432306 0)
			(unlocked yes)
			(layer "B.Fab")
			(hide yes)
			(effects
				(font
					(size 0.7874 0.5842)
					(thickness 0.127)
				)
				(justify mirror)
			)
		)
		(duplicate_pad_numbers_are_jumpers no)
		(fp_line
			(start -0.970026 -0.4699)
			(end -0.970026 0.4699)
			(stroke
				(width 0.1)
				(type default)
			)
			(layer "B.SilkS")
		)
		(fp_line
			(start -0.970026 0.4699)
			(end 0.970026 0.4699)
			(stroke
				(width 0.1)
				(type default)
			)
			(layer "B.SilkS")
		)
		(fp_line
			(start 0.970026 -0.4699)
			(end -0.970026 -0.4699)
			(stroke
				(width 0.1)
				(type default)
			)
			(layer "B.SilkS")
		)
		(fp_line
			(start 0.970026 0.4699)
			(end 0.970026 -0.4699)
			(stroke
				(width 0.1)
				(type default)
			)
			(layer "B.SilkS")
		)
		(fp_poly
			(pts
				(xy 0.970026 0.4699) (xy -0.970026 0.4699) (xy -0.970026 -0.4699) (xy 0.970026 -0.4699)
			)
			(stroke
				(width 0)
				(type default)
			)
			(fill no)
			(layer "B.CrtYd")
		)
		(fp_line
			(start -0.508 -0.3048)
			(end -0.508 0.3048)
			(stroke
				(width 0.1)
				(type default)
			)
			(layer "B.Fab")
		)
		(fp_line
			(start -0.508 0.3048)
			(end 0.508 0.3048)
			(stroke
				(width 0.1)
				(type default)
			)
			(layer "B.Fab")
		)
		(fp_line
			(start 0.508 -0.3048)
			(end -0.508 -0.3048)
			(stroke
				(width 0.1)
				(type default)
			)
			(layer "B.Fab")
		)
		(fp_line
			(start 0.508 0.3048)
			(end 0.508 -0.3048)
			(stroke
				(width 0.1)
				(type default)
			)
			(layer "B.Fab")
		)
		(pad "1" smd circle
			(at 0.500126 0 180)
			(size 0.635 0.635)
			(layers "B.Cu" "B.Mask" "B.Paste")
			(net "XP2R5V_FPGA")
		)
		(pad "2" smd circle
			(at -0.500126 0 180)
			(size 0.635 0.635)
			(layers "B.Cu" "B.Mask" "B.Paste")
			(net "SG")
		)
	)
	(footprint ""
		(layer "B.Cu")
		(at 103.347012 -37.82314)
		(property "Reference" "R197"
			(at -41.879012 1.40589 0)
			(unlocked yes)
			(layer "B.SilkS")
			(effects
				(font
					(size 0.635 0.4064)
					(thickness 0.1524)
				)
				(justify mirror)
			)
		)
		(property "Value" "VAL*"
			(at 0 3.718306 0)
			(unlocked yes)
			(layer "B.Fab")
			(hide yes)
			(effects
				(font
					(size 0.7874 0.5842)
					(thickness 0.127)
				)
				(justify mirror)
			)
		)
		(property "Device Type" "RESISTOR-G155-11000-01,100OHM,A"
			(at 0 1.432306 0)
			(unlocked yes)
			(layer "B.Fab")
			(hide yes)
			(effects
				(font
					(size 0.7874 0.5842)
					(thickness 0.127)
				)
				(justify mirror)
			)
		)
		(property "User Part Number" "PARTNUM*"
			(at 0 2.575306 0)
			(unlocked yes)
			(layer "Cmts.User")
			(hide yes)
			(effects
				(font
					(size 0.7874 0.5842)
					(thickness 0.127)
				)
				(justify mirror)
			)
		)
		(property "Tolerance" "TOL*"
			(at 0 4.861306 0)
			(unlocked yes)
			(layer "Cmts.User")
			(hide yes)
			(effects
				(font
					(size 0.7874 0.5842)
					(thickness 0.127)
				)
				(justify mirror)
			)
		)
		(duplicate_pad_numbers_are_jumpers no)
		(fp_line
			(start -0.970026 -0.4699)
			(end -0.970026 0.4699)
			(stroke
				(width 0.1)
				(type default)
			)
			(layer "B.SilkS")
		)
		(fp_line
			(start -0.970026 0.4699)
			(end 0.970026 0.4699)
			(stroke
				(width 0.1)
				(type default)
			)
			(layer "B.SilkS")
		)
		(fp_line
			(start 0.970026 -0.4699)
			(end -0.970026 -0.4699)
			(stroke
				(width 0.1)
				(type default)
			)
			(layer "B.SilkS")
		)
		(fp_line
			(start 0.970026 0.4699)
			(end 0.970026 -0.4699)
			(stroke
				(width 0.1)
				(type default)
			)
			(layer "B.SilkS")
		)
		(fp_poly
			(pts
				(xy 0.970026 0.4699) (xy -0.970026 0.4699) (xy -0.970026 -0.4699) (xy 0.970026 -0.4699)
			)
			(stroke
				(width 0)
				(type default)
			)
			(fill no)
			(layer "B.CrtYd")
		)
		(fp_line
			(start -0.508 -0.3048)
			(end -0.508 0.3048)
			(stroke
				(width 0.1)
				(type default)
			)
			(layer "B.Fab")
		)
		(fp_line
			(start -0.508 0.3048)
			(end 0.508 0.3048)
			(stroke
				(width 0.1)
				(type default)
			)
			(layer "B.Fab")
		)
		(fp_line
			(start 0.508 -0.3048)
			(end -0.508 -0.3048)
			(stroke
				(width 0.1)
				(type default)
			)
			(layer "B.Fab")
		)
		(fp_line
			(start 0.508 0.3048)
			(end 0.508 -0.3048)
			(stroke
				(width 0.1)
				(type default)
			)
			(layer "B.Fab")
		)
		(pad "1" smd circle
			(at 0.500126 0 180)
			(size 0.635 0.635)
			(layers "B.Cu" "B.Mask" "B.Paste")
			(net "MHZ125CLKP_CLKIN")
		)
		(pad "2" smd circle
			(at -0.500126 0 180)
			(size 0.635 0.635)
			(layers "B.Cu" "B.Mask" "B.Paste")
			(net "MHZ125CLKN_CLKIN")
		)
	)
	(footprint ""
		(layer "B.Cu")
		(at 83.2358 -85.979 180)
		(property "Reference" "R146"
			(at 0.6858 5.54863 0)
			(unlocked yes)
			(layer "B.SilkS")
			(effects
				(font
					(size 0.7874 0.5842)
					(thickness 0.1524)
				)
				(justify mirror)
			)
		)
		(property "Value" "VAL*"
			(at -0.02032 2.13233 180)
			(unlocked yes)
			(layer "B.Fab")
			(hide yes)
			(effects
				(font
					(size 0.7874 0.5842)
					(thickness 0.1524)
				)
				(justify mirror)
			)
		)
		(property "Tolerance" "TOL*"
			(at -0.044704 3.05435 180)
			(unlocked yes)
			(layer "Cmts.User")
			(hide yes)
			(effects
				(font
					(size 0.7874 0.5842)
					(thickness 0.1524)
				)
				(justify mirror)
			)
		)
		(property "User Part Number" "PARTNUM*"
			(at -0.02032 4.024884 180)
			(unlocked yes)
			(layer "Cmts.User")
			(hide yes)
			(effects
				(font
					(size 0.7874 0.5842)
					(thickness 0.1524)
				)
				(justify mirror)
			)
		)
		(property "Device Type" "RESISTOR-G155-11002-01,10KOHM,A"
			(at -0.008382 1.210564 180)
			(unlocked yes)
			(layer "B.Fab")
			(hide yes)
			(effects
				(font
					(size 0.7874 0.5842)
					(thickness 0.1524)
				)
				(justify mirror)
			)
		)
		(duplicate_pad_numbers_are_jumpers no)
		(fp_line
			(start 1.143 0.5588)
			(end -1.143 0.5588)
			(stroke
				(width 0.1)
				(type default)
			)
			(layer "B.SilkS")
		)
		(fp_line
			(start 1.143 -0.5588)
			(end 1.143 0.5588)
			(stroke
				(width 0.1)
				(type default)
			)
			(layer "B.SilkS")
		)
		(fp_line
			(start -1.143 0.5588)
			(end -1.143 -0.5588)
			(stroke
				(width 0.1)
				(type default)
			)
			(layer "B.SilkS")
		)
		(fp_line
			(start -1.143 -0.5588)
			(end 1.143 -0.5588)
			(stroke
				(width 0.1)
				(type default)
			)
			(layer "B.SilkS")
		)
		(fp_rect
			(start -1.143 0.5588)
			(end 1.143 -0.5588)
			(stroke
				(width 0)
				(type default)
			)
			(fill no)
			(layer "B.CrtYd")
		)
		(fp_line
			(start 0.508 0.3048)
			(end -0.508 0.3048)
			(stroke
				(width 0.1)
				(type default)
			)
			(layer "B.Fab")
		)
		(fp_line
			(start 0.508 -0.3048)
			(end 0.508 0.3048)
			(stroke
				(width 0.1)
				(type default)
			)
			(layer "B.Fab")
		)
		(fp_line
			(start -0.508 0.3048)
			(end -0.508 -0.3048)
			(stroke
				(width 0.1)
				(type default)
			)
			(layer "B.Fab")
		)
		(fp_line
			(start -0.508 -0.3048)
			(end 0.508 -0.3048)
			(stroke
				(width 0.1)
				(type default)
			)
			(layer "B.Fab")
		)
		(pad "1" smd rect
			(at 0.5334 0)
			(size 0.7112 0.6096)
			(layers "B.Cu" "B.Mask" "B.Paste")
			(net "XP3R3V_FPGA")
		)
		(pad "2" smd rect
			(at -0.5334 0)
			(size 0.7112 0.6096)
			(layers "B.Cu" "B.Mask" "B.Paste")
			(net "PCA9546_RST_N")
		)
		(zone
			(layer "B.Cu")
			(hatch none 0.5)
			(connect_pads
				(clearance 0)
			)
			(min_thickness 0.25)
			(keepout
				(tracks allowed)
				(vias not_allowed)
				(pads allowed)
				(copperpour not_allowed)
				(footprints allowed)
			)
			(placement
				(enabled no)
				(sheetname "")
			)
			(fill
				(thermal_gap 0.5)
				(thermal_bridge_width 0.5)
				(island_removal_mode 0)
			)
			(polygon
				(pts
					(xy 83.312 -86.2838) (xy 83.1596 -86.2838) (xy 83.1596 -85.6742) (xy 83.312 -85.6742)
				)
			)
		)
	)
)
